(kicad_pcb
	(version 20260206)
	(generator "pcbnew")
	(generator_version "10.0")
	(general
		(thickness 1.6)
		(legacy_teardrops no)
	)
	(paper "A4")
	(title_block
		(title "Wiwynn_Tioga_Pass_MB.brd")
		(comment 1 "Tioga Pass / footprints 2677-2683 of 4770")
	)
	(layers
		(0 "F.Cu" signal "TOP")
		(4 "In1.Cu" signal "L2GND")
		(6 "In2.Cu" signal "L3")
		(8 "In3.Cu" signal "L4GND")
		(10 "In4.Cu" signal "L5")
		(12 "In5.Cu" signal "L6GND")
		(14 "In6.Cu" signal "L7VCC")
		(16 "In7.Cu" signal "L8VCC")
		(18 "In8.Cu" signal "L9GND")
		(20 "In9.Cu" signal "L10")
		(22 "In10.Cu" signal "L11GND")
		(24 "In11.Cu" signal "L12")
		(26 "In12.Cu" signal "L13GND")
		(2 "B.Cu" signal "BOTTOM")
		(9 "F.Adhes" user "F.Adhesive")
		(11 "B.Adhes" user "B.Adhesive")
		(13 "F.Paste" user "Package Geometry/Pastemask Top")
		(15 "B.Paste" user "Package Geometry/Pastemask Bottom")
		(5 "F.SilkS" user "Ref Des/Silkscreen Top")
		(7 "B.SilkS" user "Ref Des/Silkscreen Bottom")
		(1 "F.Mask" user "Board Geometry/Soldermask Top")
		(3 "B.Mask" user "Board Geometry/Soldermask Bottom")
		(17 "Dwgs.User" user "User.Drawings")
		(19 "Cmts.User" user "User.Comments")
		(21 "Eco1.User" user "User.Eco1")
		(23 "Eco2.User" user "User.Eco2")
		(25 "Edge.Cuts" user "Board Geometry/Outline")
		(27 "Margin" user)
		(31 "F.CrtYd" user "Package Geometry/Place Bound Top")
		(29 "B.CrtYd" user "Package Geometry/Place Bound Bottom")
		(35 "F.Fab" user "Ref Des/Assembly Top")
		(33 "B.Fab" user "Ref Des/Assembly Bottom")
	)
	(footprint ""
		(layer "B.Cu")
		(at 467.791038 -6.858 90)
		(property "Reference" "C2U25"
			(at 0 0 90)
			(layer "B.SilkS")
			(hide yes)
			(effects
				(font
					(size 1.27 1.27)
				)
				(justify mirror)
			)
		)
		(property "Value" ""
			(at 0 0 90)
			(layer "B.Fab")
			(effects
				(font
					(size 1.27 1.27)
				)
				(justify mirror)
			)
		)
		(duplicate_pad_numbers_are_jumpers no)
		(fp_poly
			(pts
				(xy -0.3048 -0.1016) (xy -0.3048 0.9906) (xy 0.3048 0.9906) (xy 0.3048 -0.1016)
			)
			(stroke
				(width 0)
				(type default)
			)
			(fill no)
			(layer "B.CrtYd")
		)
		(fp_line
			(start 0.3048 -0.1016)
			(end 0.3048 0.9906)
			(stroke
				(width 0.1)
				(type default)
			)
			(layer "B.Fab")
		)
		(fp_line
			(start -0.3048 -0.1016)
			(end 0.3048 -0.1016)
			(stroke
				(width 0.1)
				(type default)
			)
			(layer "B.Fab")
		)
		(fp_line
			(start 0.3048 0.9906)
			(end -0.3048 0.9906)
			(stroke
				(width 0.1)
				(type default)
			)
			(layer "B.Fab")
		)
		(fp_line
			(start -0.3048 0.9906)
			(end -0.3048 -0.1016)
			(stroke
				(width 0.1)
				(type default)
			)
			(layer "B.Fab")
		)
		(pad "1" smd rect
			(at 0 0 270)
			(size 0.508 0.508)
			(layers "B.Cu" "B.Mask" "B.Paste")
			(net "P3V3")
		)
		(pad "2" smd rect
			(at 0 0.889 270)
			(size 0.508 0.508)
			(layers "B.Cu" "B.Mask" "B.Paste")
			(net "GND")
		)
		(zone
			(layer "B.Cu")
			(hatch none 0.5)
			(connect_pads
				(clearance 0)
			)
			(min_thickness 0.25)
			(keepout
				(tracks allowed)
				(vias not_allowed)
				(pads allowed)
				(copperpour not_allowed)
				(footprints allowed)
			)
			(placement
				(enabled no)
				(sheetname "")
			)
			(fill
				(thermal_gap 0.5)
				(thermal_bridge_width 0.5)
				(island_removal_mode 0)
			)
			(polygon
				(pts
					(xy 468.045038 -7.112) (xy 468.045038 -6.604) (xy 468.426038 -6.604) (xy 468.426038 -7.112)
				)
			)
		)
		(zone
			(layer "B.Cu")
			(hatch none 0.5)
			(connect_pads
				(clearance 0)
			)
			(min_thickness 0.25)
			(keepout
				(tracks not_allowed)
				(vias allowed)
				(pads allowed)
				(copperpour not_allowed)
				(footprints allowed)
			)
			(placement
				(enabled no)
				(sheetname "")
			)
			(fill
				(thermal_gap 0.5)
				(thermal_bridge_width 0.5)
				(island_removal_mode 0)
			)
			(polygon
				(pts
					(xy 468.426038 -7.112) (xy 468.426038 -6.604) (xy 468.045038 -6.604) (xy 468.045038 -7.112)
				)
			)
		)
	)
	(footprint ""
		(layer "B.Cu")
		(at 454.4822 -42.545 180)
		(property "Reference" "R25W145"
			(at 0.8382 -0.67818 180)
			(unlocked yes)
			(layer "B.SilkS")
			(effects
				(font
					(size 0.4064 0.254)
					(thickness 0.1524)
				)
				(justify left mirror)
			)
		)
		(property "Value" ""
			(at 0 0 0)
			(layer "B.Fab")
			(effects
				(font
					(size 1.27 1.27)
				)
				(justify mirror)
			)
		)
		(duplicate_pad_numbers_are_jumpers no)
		(fp_poly
			(pts
				(xy 0.2794 -0.1016) (xy -0.2794 -0.1016) (xy -0.2794 0.9906) (xy 0.2794 0.9906)
			)
			(stroke
				(width 0)
				(type default)
			)
			(fill no)
			(layer "B.CrtYd")
		)
		(fp_line
			(start 0.2794 0.9906)
			(end -0.2794 0.9906)
			(stroke
				(width 0.1)
				(type default)
			)
			(layer "B.Fab")
		)
		(fp_line
			(start 0.2794 -0.1016)
			(end 0.2794 0.9906)
			(stroke
				(width 0.1)
				(type default)
			)
			(layer "B.Fab")
		)
		(fp_line
			(start -0.2794 0.9906)
			(end -0.2794 -0.1016)
			(stroke
				(width 0.1)
				(type default)
			)
			(layer "B.Fab")
		)
		(fp_line
			(start -0.2794 -0.1016)
			(end 0.2794 -0.1016)
			(stroke
				(width 0.1)
				(type default)
			)
			(layer "B.Fab")
		)
		(pad "1" smd rect
			(at 0 0)
			(size 0.508 0.508)
			(layers "B.Cu" "B.Mask" "B.Paste")
			(net "RST_SYSTEM_BTN_R_N")
		)
		(pad "2" smd rect
			(at 0 0.889)
			(size 0.508 0.508)
			(layers "B.Cu" "B.Mask" "B.Paste")
			(net "RST_SYSTEM_BTN_N")
		)
		(zone
			(layer "B.Cu")
			(hatch none 0.5)
			(connect_pads
				(clearance 0)
			)
			(min_thickness 0.25)
			(keepout
				(tracks not_allowed)
				(vias allowed)
				(pads allowed)
				(copperpour not_allowed)
				(footprints allowed)
			)
			(placement
				(enabled no)
				(sheetname "")
			)
			(fill
				(thermal_gap 0.5)
				(thermal_bridge_width 0.5)
				(island_removal_mode 0)
			)
			(polygon
				(pts
					(xy 454.2282 -43.18) (xy 454.7362 -43.18) (xy 454.7362 -42.799) (xy 454.2282 -42.799)
				)
			)
		)
		(zone
			(layer "B.Cu")
			(hatch none 0.5)
			(connect_pads
				(clearance 0)
			)
			(min_thickness 0.25)
			(keepout
				(tracks allowed)
				(vias not_allowed)
				(pads allowed)
				(copperpour not_allowed)
				(footprints allowed)
			)
			(placement
				(enabled no)
				(sheetname "")
			)
			(fill
				(thermal_gap 0.5)
				(thermal_bridge_width 0.5)
				(island_removal_mode 0)
			)
			(polygon
				(pts
					(xy 454.2282 -42.799) (xy 454.7362 -42.799) (xy 454.7362 -43.18) (xy 454.2282 -43.18)
				)
			)
		)
	)
	(footprint ""
		(layer "B.Cu")
		(at 413.639 -6.1976 180)
		(property "Reference" "Q1P2"
			(at 0.229362 -1.2065 180)
			(unlocked yes)
			(layer "B.SilkS")
			(effects
				(font
					(size 0.4064 0.254)
					(thickness 0.1524)
				)
				(justify left mirror)
			)
		)
		(property "Value" ""
			(at 0 0 0)
			(layer "B.Fab")
			(effects
				(font
					(size 1.27 1.27)
				)
				(justify mirror)
			)
		)
		(duplicate_pad_numbers_are_jumpers no)
		(fp_line
			(start -0.381 0.635)
			(end -0.381 1.27)
			(stroke
				(width 0.1524)
				(type default)
			)
			(layer "B.SilkS")
		)
		(fp_line
			(start -0.9525 2.4765)
			(end -1.778 2.4765)
			(stroke
				(width 0.1524)
				(type default)
			)
			(layer "B.SilkS")
		)
		(fp_line
			(start -0.9525 -0.5715)
			(end -1.778 -0.5715)
			(stroke
				(width 0.1524)
				(type default)
			)
			(layer "B.SilkS")
		)
		(fp_line
			(start -1.778 2.4765)
			(end -1.778 1.5875)
			(stroke
				(width 0.1524)
				(type default)
			)
			(layer "B.SilkS")
		)
		(fp_line
			(start -1.778 -0.5715)
			(end -1.778 0.3175)
			(stroke
				(width 0.1524)
				(type default)
			)
			(layer "B.SilkS")
		)
		(fp_circle
			(center 0.9525 -0.9271)
			(end 0.8255 -0.9271)
			(stroke
				(width 0.254)
				(type default)
			)
			(fill no)
			(layer "B.SilkS")
		)
		(fp_poly
			(pts
				(xy -1.778 2.4765) (xy -0.381 2.4765) (xy -0.381 -0.5715) (xy -1.778 -0.5715)
			)
			(stroke
				(width 0)
				(type default)
			)
			(fill no)
			(layer "B.CrtYd")
		)
		(fp_line
			(start -0.381 2.4765)
			(end -1.778 2.4765)
			(stroke
				(width 0.1)
				(type default)
			)
			(layer "B.Fab")
		)
		(fp_line
			(start -0.381 -0.5715)
			(end -0.381 2.4765)
			(stroke
				(width 0.1)
				(type default)
			)
			(layer "B.Fab")
		)
		(fp_line
			(start -1.778 2.4765)
			(end -1.778 -0.5715)
			(stroke
				(width 0.1)
				(type default)
			)
			(layer "B.Fab")
		)
		(fp_line
			(start -1.778 -0.5715)
			(end -0.381 -0.5715)
			(stroke
				(width 0.1)
				(type default)
			)
			(layer "B.Fab")
		)
		(fp_circle
			(center 0.9525 -0.9271)
			(end 0.8255 -0.9271)
			(stroke
				(width 0.254)
				(type default)
			)
			(fill no)
			(layer "B.Fab")
		)
		(pad "1" smd rect
			(at 0 0)
			(size 1.143 0.508)
			(layers "B.Cu" "B.Mask" "B.Paste")
			(net "PWRGD_P5V_N")
		)
		(pad "2" smd rect
			(at 0 1.905)
			(size 1.143 0.508)
			(layers "B.Cu" "B.Mask" "B.Paste")
			(net "GND")
		)
		(pad "3" smd rect
			(at -2.159 0.9525)
			(size 1.143 0.508)
			(layers "B.Cu" "B.Mask" "B.Paste")
			(net "PWRGD_P5V_R")
		)
	)
	(footprint ""
		(layer "B.Cu")
		(at 452.8058 -153.6446 180)
		(property "Reference" "R9A3"
			(at 0 0 0)
			(layer "B.SilkS")
			(hide yes)
			(effects
				(font
					(size 1.27 1.27)
				)
				(justify mirror)
			)
		)
		(property "Value" ""
			(at 0 0 0)
			(layer "B.Fab")
			(effects
				(font
					(size 1.27 1.27)
				)
				(justify mirror)
			)
		)
		(duplicate_pad_numbers_are_jumpers no)
		(fp_poly
			(pts
				(xy 0.2794 -0.1016) (xy -0.2794 -0.1016) (xy -0.2794 0.9906) (xy 0.2794 0.9906)
			)
			(stroke
				(width 0)
				(type default)
			)
			(fill no)
			(layer "B.CrtYd")
		)
		(fp_line
			(start 0.2794 0.9906)
			(end -0.2794 0.9906)
			(stroke
				(width 0.1)
				(type default)
			)
			(layer "B.Fab")
		)
		(fp_line
			(start 0.2794 -0.1016)
			(end 0.2794 0.9906)
			(stroke
				(width 0.1)
				(type default)
			)
			(layer "B.Fab")
		)
		(fp_line
			(start -0.2794 0.9906)
			(end -0.2794 -0.1016)
			(stroke
				(width 0.1)
				(type default)
			)
			(layer "B.Fab")
		)
		(fp_line
			(start -0.2794 -0.1016)
			(end 0.2794 -0.1016)
			(stroke
				(width 0.1)
				(type default)
			)
			(layer "B.Fab")
		)
		(pad "1" smd rect
			(at 0 0)
			(size 0.508 0.508)
			(layers "B.Cu" "B.Mask" "B.Paste")
			(net "XDP_PCH_CPU_TCK0")
		)
		(pad "2" smd rect
			(at 0 0.889)
			(size 0.508 0.508)
			(layers "B.Cu" "B.Mask" "B.Paste")
			(net "XDP_CPU_TCK0")
		)
		(zone
			(layer "B.Cu")
			(hatch none 0.5)
			(connect_pads
				(clearance 0)
			)
			(min_thickness 0.25)
			(keepout
				(tracks not_allowed)
				(vias allowed)
				(pads allowed)
				(copperpour not_allowed)
				(footprints allowed)
			)
			(placement
				(enabled no)
				(sheetname "")
			)
			(fill
				(thermal_gap 0.5)
				(thermal_bridge_width 0.5)
				(island_removal_mode 0)
			)
			(polygon
				(pts
					(xy 452.5518 -154.2796) (xy 453.0598 -154.2796) (xy 453.0598 -153.8986) (xy 452.5518 -153.8986)
				)
			)
		)
		(zone
			(layer "B.Cu")
			(hatch none 0.5)
			(connect_pads
				(clearance 0)
			)
			(min_thickness 0.25)
			(keepout
				(tracks allowed)
				(vias not_allowed)
				(pads allowed)
				(copperpour not_allowed)
				(footprints allowed)
			)
			(placement
				(enabled no)
				(sheetname "")
			)
			(fill
				(thermal_gap 0.5)
				(thermal_bridge_width 0.5)
				(island_removal_mode 0)
			)
			(polygon
				(pts
					(xy 452.5518 -153.8986) (xy 453.0598 -153.8986) (xy 453.0598 -154.2796) (xy 452.5518 -154.2796)
				)
			)
		)
	)
	(footprint ""
		(layer "B.Cu")
		(at 165.8874 2.286 -90)
		(property "Reference" "R6U14"
			(at 0 0 90)
			(layer "B.SilkS")
			(hide yes)
			(effects
				(font
					(size 1.27 1.27)
				)
				(justify mirror)
			)
		)
		(property "Value" ""
			(at 0 0 90)
			(layer "B.Fab")
			(effects
				(font
					(size 1.27 1.27)
				)
				(justify mirror)
			)
		)
		(duplicate_pad_numbers_are_jumpers no)
		(fp_poly
			(pts
				(xy 0.2794 -0.1016) (xy -0.2794 -0.1016) (xy -0.2794 0.9906) (xy 0.2794 0.9906)
			)
			(stroke
				(width 0)
				(type default)
			)
			(fill no)
			(layer "B.CrtYd")
		)
		(fp_line
			(start -0.2794 0.9906)
			(end -0.2794 -0.1016)
			(stroke
				(width 0.1)
				(type default)
			)
			(layer "B.Fab")
		)
		(fp_line
			(start 0.2794 0.9906)
			(end -0.2794 0.9906)
			(stroke
				(width 0.1)
				(type default)
			)
			(layer "B.Fab")
		)
		(fp_line
			(start -0.2794 -0.1016)
			(end 0.2794 -0.1016)
			(stroke
				(width 0.1)
				(type default)
			)
			(layer "B.Fab")
		)
		(fp_line
			(start 0.2794 -0.1016)
			(end 0.2794 0.9906)
			(stroke
				(width 0.1)
				(type default)
			)
			(layer "B.Fab")
		)
		(pad "1" smd rect
			(at 0 0 90)
			(size 0.508 0.508)
			(layers "B.Cu" "B.Mask" "B.Paste")
			(net "SMB_DDR_GHJ_VPP_SDA_R")
		)
		(pad "2" smd rect
			(at 0 0.889 90)
			(size 0.508 0.508)
			(layers "B.Cu" "B.Mask" "B.Paste")
			(net "SMB_DDR_GHJ_VPP_SDA")
		)
		(zone
			(layer "B.Cu")
			(hatch none 0.5)
			(connect_pads
				(clearance 0)
			)
			(min_thickness 0.25)
			(keepout
				(tracks not_allowed)
				(vias allowed)
				(pads allowed)
				(copperpour not_allowed)
				(footprints allowed)
			)
			(placement
				(enabled no)
				(sheetname "")
			)
			(fill
				(thermal_gap 0.5)
				(thermal_bridge_width 0.5)
				(island_removal_mode 0)
			)
			(polygon
				(pts
					(xy 165.2524 2.54) (xy 165.2524 2.032) (xy 165.6334 2.032) (xy 165.6334 2.54)
				)
			)
		)
		(zone
			(layer "B.Cu")
			(hatch none 0.5)
			(connect_pads
				(clearance 0)
			)
			(min_thickness 0.25)
			(keepout
				(tracks allowed)
				(vias not_allowed)
				(pads allowed)
				(copperpour not_allowed)
				(footprints allowed)
			)
			(placement
				(enabled no)
				(sheetname "")
			)
			(fill
				(thermal_gap 0.5)
				(thermal_bridge_width 0.5)
				(island_removal_mode 0)
			)
			(polygon
				(pts
					(xy 165.6334 2.54) (xy 165.6334 2.032) (xy 165.2524 2.032) (xy 165.2524 2.54)
				)
			)
		)
	)
	(footprint ""
		(layer "B.Cu")
		(at 372.11 -135.1661 -90)
		(property "Reference" "FB3M2"
			(at 0 0 90)
			(layer "B.SilkS")
			(hide yes)
			(effects
				(font
					(size 1.27 1.27)
				)
				(justify mirror)
			)
		)
		(property "Value" ""
			(at 0 0 90)
			(layer "B.Fab")
			(effects
				(font
					(size 1.27 1.27)
				)
				(justify mirror)
			)
		)
		(duplicate_pad_numbers_are_jumpers no)
		(fp_poly
			(pts
				(xy 0.15113 -0.47498) (xy -1.59893 -0.47498) (xy -1.59893 0.47498) (xy 0.15113 0.47498)
			)
			(stroke
				(width 0)
				(type default)
			)
			(fill no)
			(layer "B.CrtYd")
		)
		(fp_line
			(start -1.59893 0.47498)
			(end 0.15113 0.47498)
			(stroke
				(width 0.1)
				(type default)
			)
			(layer "B.Fab")
		)
		(fp_line
			(start 0.15113 0.47498)
			(end 0.15113 -0.47498)
			(stroke
				(width 0.1)
				(type default)
			)
			(layer "B.Fab")
		)
		(fp_line
			(start -1.59893 -0.47498)
			(end -1.59893 0.47498)
			(stroke
				(width 0.1)
				(type default)
			)
			(layer "B.Fab")
		)
		(fp_line
			(start 0.15113 -0.47498)
			(end -1.59893 -0.47498)
			(stroke
				(width 0.1)
				(type default)
			)
			(layer "B.Fab")
		)
		(pad "1" smd rect
			(at 0 0 90)
			(size 0.9398 0.9398)
			(layers "B.Cu" "B.Mask" "B.Paste")
			(net "P1V05_PCH_STBY")
		)
		(pad "2" smd rect
			(at -1.4478 0 90)
			(size 0.9398 0.9398)
			(layers "B.Cu" "B.Mask" "B.Paste")
			(net "P1V05_PCH_STBY_VCCA_PLL0")
		)
		(zone
			(layer "B.Cu")
			(hatch none 0.5)
			(connect_pads
				(clearance 0)
			)
			(min_thickness 0.25)
			(keepout
				(tracks allowed)
				(vias not_allowed)
				(pads allowed)
				(copperpour not_allowed)
				(footprints allowed)
			)
			(placement
				(enabled no)
				(sheetname "")
			)
			(fill
				(thermal_gap 0.5)
				(thermal_bridge_width 0.5)
				(island_removal_mode 0)
			)
			(polygon
				(pts
					(xy 371.6401 -135.636) (xy 372.5799 -135.636) (xy 372.5799 -136.144) (xy 371.6401 -136.144)
				)
			)
		)
		(zone
			(layer "B.Cu")
			(hatch none 0.5)
			(connect_pads
				(clearance 0)
			)
			(min_thickness 0.25)
			(keepout
				(tracks not_allowed)
				(vias allowed)
				(pads allowed)
				(copperpour not_allowed)
				(footprints allowed)
			)
			(placement
				(enabled no)
				(sheetname "")
			)
			(fill
				(thermal_gap 0.5)
				(thermal_bridge_width 0.5)
				(island_removal_mode 0)
			)
			(polygon
				(pts
					(xy 371.6401 -135.636) (xy 372.5799 -135.636) (xy 372.5799 -136.144) (xy 371.6401 -136.144)
				)
			)
		)
	)
	(footprint ""
		(layer "B.Cu")
		(at 331.343 -11.7094)
		(property "Reference" "R4U1"
			(at 0 0 0)
			(layer "B.SilkS")
			(hide yes)
			(effects
				(font
					(size 1.27 1.27)
				)
				(justify mirror)
			)
		)
		(property "Value" ""
			(at 0 0 0)
			(layer "B.Fab")
			(effects
				(font
					(size 1.27 1.27)
				)
				(justify mirror)
			)
		)
		(duplicate_pad_numbers_are_jumpers no)
		(fp_poly
			(pts
				(xy 0.2794 -0.1016) (xy -0.2794 -0.1016) (xy -0.2794 0.9906) (xy 0.2794 0.9906)
			)
			(stroke
				(width 0)
				(type default)
			)
			(fill no)
			(layer "B.CrtYd")
		)
		(fp_line
			(start -0.2794 -0.1016)
			(end 0.2794 -0.1016)
			(stroke
				(width 0.1)
				(type default)
			)
			(layer "B.Fab")
		)
		(fp_line
			(start -0.2794 0.9906)
			(end -0.2794 -0.1016)
			(stroke
				(width 0.1)
				(type default)
			)
			(layer "B.Fab")
		)
		(fp_line
			(start 0.2794 -0.1016)
			(end 0.2794 0.9906)
			(stroke
				(width 0.1)
				(type default)
			)
			(layer "B.Fab")
		)
		(fp_line
			(start 0.2794 0.9906)
			(end -0.2794 0.9906)
			(stroke
				(width 0.1)
				(type default)
			)
			(layer "B.Fab")
		)
		(pad "1" smd rect
			(at 0 0 180)
			(size 0.508 0.508)
			(layers "B.Cu" "B.Mask" "B.Paste")
			(net "P3V3_STBY")
		)
		(pad "2" smd rect
			(at 0 0.889 180)
			(size 0.508 0.508)
			(layers "B.Cu" "B.Mask" "B.Paste")
			(net "FM_MEM_THERM_EVENT_LVT3_N")
		)
		(zone
			(layer "B.Cu")
			(hatch none 0.5)
			(connect_pads
				(clearance 0)
			)
			(min_thickness 0.25)
			(keepout
				(tracks allowed)
				(vias not_allowed)
				(pads allowed)
				(copperpour not_allowed)
				(footprints allowed)
			)
			(placement
				(enabled no)
				(sheetname "")
			)
			(fill
				(thermal_gap 0.5)
				(thermal_bridge_width 0.5)
				(island_removal_mode 0)
			)
			(polygon
				(pts
					(xy 331.597 -11.4554) (xy 331.089 -11.4554) (xy 331.089 -11.0744) (xy 331.597 -11.0744)
				)
			)
		)
		(zone
			(layer "B.Cu")
			(hatch none 0.5)
			(connect_pads
				(clearance 0)
			)
			(min_thickness 0.25)
			(keepout
				(tracks not_allowed)
				(vias allowed)
				(pads allowed)
				(copperpour not_allowed)
				(footprints allowed)
			)
			(placement
				(enabled no)
				(sheetname "")
			)
			(fill
				(thermal_gap 0.5)
				(thermal_bridge_width 0.5)
				(island_removal_mode 0)
			)
			(polygon
				(pts
					(xy 331.597 -11.0744) (xy 331.089 -11.0744) (xy 331.089 -11.4554) (xy 331.597 -11.4554)
				)
			)
		)
	)
)
